(kicad_pcb
	(version 20260206)
	(generator "pcbnew")
	(generator_version "10.0")
	(general
		(thickness 1.6)
		(legacy_teardrops no)
	)
	(paper "A4")
	(title_block
		(title "04192023_DAF0TMB3IC0_F0TG_MB_C_brd_V02_OCP.brd")
		(comment 1 "Grand Teton / footprint 4167 of 8354 (J17), pads 227-291 of 291")
	)
	(layers
		(0 "F.Cu" signal "TOP")
		(4 "In1.Cu" signal "GND")
		(6 "In2.Cu" signal "IN1")
		(8 "In3.Cu" signal "GND1")
		(10 "In4.Cu" signal "IN2")
		(12 "In5.Cu" signal "GND2")
		(14 "In6.Cu" signal "IN3")
		(16 "In7.Cu" signal "GND3")
		(18 "In8.Cu" signal "VCC")
		(20 "In9.Cu" signal "VCC1")
		(22 "In10.Cu" signal "GND4")
		(24 "In11.Cu" signal "IN4")
		(26 "In12.Cu" signal "GND5")
		(28 "In13.Cu" signal "IN5")
		(30 "In14.Cu" signal "GND6")
		(32 "In15.Cu" signal "IN6")
		(34 "In16.Cu" signal "GND7")
		(2 "B.Cu" signal "BOTTOM")
		(9 "F.Adhes" user "F.Adhesive")
		(11 "B.Adhes" user "B.Adhesive")
		(13 "F.Paste" user "Package Geometry/Pastemask Top")
		(15 "B.Paste" user "Package Geometry/Pastemask Bottom")
		(5 "F.SilkS" user "Ref Des/Silkscreen Top")
		(7 "B.SilkS" user "Ref Des/Silkscreen Bottom")
		(1 "F.Mask" user "Board Geometry/Soldermask Top")
		(3 "B.Mask" user "Board Geometry/Soldermask Bottom")
		(17 "Dwgs.User" user "User.Drawings")
		(19 "Cmts.User" user "User.Comments")
		(21 "Eco1.User" user "User.Eco1")
		(23 "Eco2.User" user "User.Eco2")
		(25 "Edge.Cuts" user "Board Geometry/Outline")
		(27 "Margin" user)
		(31 "F.CrtYd" user "Package Geometry/Place Bound Top")
		(29 "B.CrtYd" user "Package Geometry/Place Bound Bottom")
		(35 "F.Fab" user "Ref Des/Assembly Top")
		(33 "B.Fab" user "Ref Des/Assembly Bottom")
	)
	(footprint ""
		(layer "F.Cu")
		(at 290.230052 -255.560068 180)
		(property "Reference" "J17"
			(at -2.2098 -81.984088 0)
			(unlocked yes)
			(layer "F.SilkS")
			(effects
				(font
					(size 0.7874 0.5842)
					(thickness 0.1524)
				)
			)
		)
		(property "Value" ""
			(at 0 0 180)
			(layer "F.Fab")
			(effects
				(font
					(size 1.27 1.27)
				)
			)
		)
		(duplicate_pad_numbers_are_jumpers no)
		(pad "227" smd rect
			(at 2.050034 11.474958 90)
			(size 0.519938 1.4986)
			(layers "F.Cu" "F.Mask" "F.Paste")
			(net "M_C_CPU0_SB_PAR")
		)
		(pad "228" smd rect
			(at 2.050034 12.325096 90)
			(size 0.519938 1.4986)
			(layers "F.Cu" "F.Mask" "F.Paste")
			(net "GND")
		)
		(pad "229" smd rect
			(at 2.050034 13.17498 90)
			(size 0.519938 1.4986)
			(layers "F.Cu" "F.Mask" "F.Paste")
			(net "M_C_CPU0_SB_CS_N<1>")
		)
		(pad "230" smd rect
			(at 2.050034 14.025118 90)
			(size 0.519938 1.4986)
			(layers "F.Cu" "F.Mask" "F.Paste")
			(net "GND")
		)
		(pad "231" smd rect
			(at 2.050034 14.875002 90)
			(size 0.519938 1.4986)
			(layers "F.Cu" "F.Mask" "F.Paste")
			(net "Net_2282")
		)
		(pad "232" smd rect
			(at 2.050034 15.724886 90)
			(size 0.519938 1.4986)
			(layers "F.Cu" "F.Mask" "F.Paste")
			(net "Net_2283")
		)
		(pad "233" smd rect
			(at 2.050034 16.575024 90)
			(size 0.519938 1.4986)
			(layers "F.Cu" "F.Mask" "F.Paste")
			(net "GND")
		)
		(pad "234" smd rect
			(at 2.050034 17.424908 90)
			(size 0.519938 1.4986)
			(layers "F.Cu" "F.Mask" "F.Paste")
			(net "M_C_CPU0_SB_CB<6>")
		)
		(pad "235" smd rect
			(at 2.050034 18.275046 90)
			(size 0.519938 1.4986)
			(layers "F.Cu" "F.Mask" "F.Paste")
			(net "GND")
		)
		(pad "236" smd rect
			(at 2.050034 19.12493 90)
			(size 0.519938 1.4986)
			(layers "F.Cu" "F.Mask" "F.Paste")
			(net "M_C_CPU0_SB_CB<7>")
		)
		(pad "237" smd rect
			(at 2.050034 19.975068 90)
			(size 0.519938 1.4986)
			(layers "F.Cu" "F.Mask" "F.Paste")
			(net "GND")
		)
		(pad "238" smd rect
			(at 2.050034 20.824952 90)
			(size 0.519938 1.4986)
			(layers "F.Cu" "F.Mask" "F.Paste")
			(net "M_C_CPU0_SB_DQS_DN<4>")
		)
		(pad "239" smd rect
			(at 2.050034 21.67509 90)
			(size 0.519938 1.4986)
			(layers "F.Cu" "F.Mask" "F.Paste")
			(net "M_C_CPU0_SB_DQS_DP<4>")
		)
		(pad "240" smd rect
			(at 2.050034 22.524974 90)
			(size 0.519938 1.4986)
			(layers "F.Cu" "F.Mask" "F.Paste")
			(net "GND")
		)
		(pad "241" smd rect
			(at 2.050034 23.375112 90)
			(size 0.519938 1.4986)
			(layers "F.Cu" "F.Mask" "F.Paste")
			(net "M_C_CPU0_SB_CB<2>")
		)
		(pad "242" smd rect
			(at 2.050034 24.224996 90)
			(size 0.519938 1.4986)
			(layers "F.Cu" "F.Mask" "F.Paste")
			(net "GND")
		)
		(pad "243" smd rect
			(at 2.050034 25.07488 90)
			(size 0.519938 1.4986)
			(layers "F.Cu" "F.Mask" "F.Paste")
			(net "M_C_CPU0_SB_CB<3>")
		)
		(pad "244" smd rect
			(at 2.050034 25.925018 90)
			(size 0.519938 1.4986)
			(layers "F.Cu" "F.Mask" "F.Paste")
			(net "GND")
		)
		(pad "245" smd rect
			(at 2.050034 26.774902 90)
			(size 0.519938 1.4986)
			(layers "F.Cu" "F.Mask" "F.Paste")
			(net "M_C_CPU0_SB_DQ<2>")
		)
		(pad "246" smd rect
			(at 2.050034 27.62504 90)
			(size 0.519938 1.4986)
			(layers "F.Cu" "F.Mask" "F.Paste")
			(net "GND")
		)
		(pad "247" smd rect
			(at 2.050034 28.474924 90)
			(size 0.519938 1.4986)
			(layers "F.Cu" "F.Mask" "F.Paste")
			(net "M_C_CPU0_SB_DQ<3>")
		)
		(pad "248" smd rect
			(at 2.050034 29.325062 90)
			(size 0.519938 1.4986)
			(layers "F.Cu" "F.Mask" "F.Paste")
			(net "GND")
		)
		(pad "249" smd rect
			(at 2.050034 30.174946 90)
			(size 0.519938 1.4986)
			(layers "F.Cu" "F.Mask" "F.Paste")
			(net "M_C_CPU0_SB_DQS_DN<5>")
		)
		(pad "250" smd rect
			(at 2.050034 31.025084 90)
			(size 0.519938 1.4986)
			(layers "F.Cu" "F.Mask" "F.Paste")
			(net "M_C_CPU0_SB_DQS_DP<5>")
		)
		(pad "251" smd rect
			(at 2.050034 31.874968 90)
			(size 0.519938 1.4986)
			(layers "F.Cu" "F.Mask" "F.Paste")
			(net "GND")
		)
		(pad "252" smd rect
			(at 2.050034 32.725106 90)
			(size 0.519938 1.4986)
			(layers "F.Cu" "F.Mask" "F.Paste")
			(net "M_C_CPU0_SB_DQ<6>")
		)
		(pad "253" smd rect
			(at 2.050034 33.57499 90)
			(size 0.519938 1.4986)
			(layers "F.Cu" "F.Mask" "F.Paste")
			(net "GND")
		)
		(pad "254" smd rect
			(at 2.050034 34.425128 90)
			(size 0.519938 1.4986)
			(layers "F.Cu" "F.Mask" "F.Paste")
			(net "M_C_CPU0_SB_DQ<7>")
		)
		(pad "255" smd rect
			(at 2.050034 35.275012 90)
			(size 0.519938 1.4986)
			(layers "F.Cu" "F.Mask" "F.Paste")
			(net "GND")
		)
		(pad "256" smd rect
			(at 2.050034 36.124896 90)
			(size 0.519938 1.4986)
			(layers "F.Cu" "F.Mask" "F.Paste")
			(net "M_C_CPU0_SB_DQ<10>")
		)
		(pad "257" smd rect
			(at 2.050034 36.975034 90)
			(size 0.519938 1.4986)
			(layers "F.Cu" "F.Mask" "F.Paste")
			(net "GND")
		)
		(pad "258" smd rect
			(at 2.050034 37.824918 90)
			(size 0.519938 1.4986)
			(layers "F.Cu" "F.Mask" "F.Paste")
			(net "M_C_CPU0_SB_DQ<11>")
		)
		(pad "259" smd rect
			(at 2.050034 38.675056 90)
			(size 0.519938 1.4986)
			(layers "F.Cu" "F.Mask" "F.Paste")
			(net "GND")
		)
		(pad "260" smd rect
			(at 2.050034 39.52494 90)
			(size 0.519938 1.4986)
			(layers "F.Cu" "F.Mask" "F.Paste")
			(net "M_C_CPU0_SB_DQS_DN<6>")
		)
		(pad "261" smd rect
			(at 2.050034 40.375078 90)
			(size 0.519938 1.4986)
			(layers "F.Cu" "F.Mask" "F.Paste")
			(net "M_C_CPU0_SB_DQS_DP<6>")
		)
		(pad "262" smd rect
			(at 2.050034 41.224962 90)
			(size 0.519938 1.4986)
			(layers "F.Cu" "F.Mask" "F.Paste")
			(net "GND")
		)
		(pad "263" smd rect
			(at 2.050034 42.0751 90)
			(size 0.519938 1.4986)
			(layers "F.Cu" "F.Mask" "F.Paste")
			(net "M_C_CPU0_SB_DQ<14>")
		)
		(pad "264" smd rect
			(at 2.050034 42.924984 90)
			(size 0.519938 1.4986)
			(layers "F.Cu" "F.Mask" "F.Paste")
			(net "GND")
		)
		(pad "265" smd rect
			(at 2.050034 43.775122 90)
			(size 0.519938 1.4986)
			(layers "F.Cu" "F.Mask" "F.Paste")
			(net "M_C_CPU0_SB_DQ<15>")
		)
		(pad "266" smd rect
			(at 2.050034 44.625006 90)
			(size 0.519938 1.4986)
			(layers "F.Cu" "F.Mask" "F.Paste")
			(net "GND")
		)
		(pad "267" smd rect
			(at 2.050034 45.47489 90)
			(size 0.519938 1.4986)
			(layers "F.Cu" "F.Mask" "F.Paste")
			(net "M_C_CPU0_SB_DQ<18>")
		)
		(pad "268" smd rect
			(at 2.050034 46.325028 90)
			(size 0.519938 1.4986)
			(layers "F.Cu" "F.Mask" "F.Paste")
			(net "GND")
		)
		(pad "269" smd rect
			(at 2.050034 47.174912 90)
			(size 0.519938 1.4986)
			(layers "F.Cu" "F.Mask" "F.Paste")
			(net "M_C_CPU0_SB_DQ<19>")
		)
		(pad "270" smd rect
			(at 2.050034 48.02505 90)
			(size 0.519938 1.4986)
			(layers "F.Cu" "F.Mask" "F.Paste")
			(net "GND")
		)
		(pad "271" smd rect
			(at 2.050034 48.874934 90)
			(size 0.519938 1.4986)
			(layers "F.Cu" "F.Mask" "F.Paste")
			(net "M_C_CPU0_SB_DQS_DN<7>")
		)
		(pad "272" smd rect
			(at 2.050034 49.725072 90)
			(size 0.519938 1.4986)
			(layers "F.Cu" "F.Mask" "F.Paste")
			(net "M_C_CPU0_SB_DQS_DP<7>")
		)
		(pad "273" smd rect
			(at 2.050034 50.574956 90)
			(size 0.519938 1.4986)
			(layers "F.Cu" "F.Mask" "F.Paste")
			(net "GND")
		)
		(pad "274" smd rect
			(at 2.050034 51.425094 90)
			(size 0.519938 1.4986)
			(layers "F.Cu" "F.Mask" "F.Paste")
			(net "M_C_CPU0_SB_DQ<22>")
		)
		(pad "275" smd rect
			(at 2.050034 52.274978 90)
			(size 0.519938 1.4986)
			(layers "F.Cu" "F.Mask" "F.Paste")
			(net "GND")
		)
		(pad "276" smd rect
			(at 2.050034 53.125116 90)
			(size 0.519938 1.4986)
			(layers "F.Cu" "F.Mask" "F.Paste")
			(net "M_C_CPU0_SB_DQ<23>")
		)
		(pad "277" smd rect
			(at 2.050034 53.975 90)
			(size 0.519938 1.4986)
			(layers "F.Cu" "F.Mask" "F.Paste")
			(net "GND")
		)
		(pad "278" smd rect
			(at 2.050034 54.824884 90)
			(size 0.519938 1.4986)
			(layers "F.Cu" "F.Mask" "F.Paste")
			(net "M_C_CPU0_SB_DQ<26>")
		)
		(pad "279" smd rect
			(at 2.050034 55.675022 90)
			(size 0.519938 1.4986)
			(layers "F.Cu" "F.Mask" "F.Paste")
			(net "GND")
		)
		(pad "280" smd rect
			(at 2.050034 56.524906 90)
			(size 0.519938 1.4986)
			(layers "F.Cu" "F.Mask" "F.Paste")
			(net "M_C_CPU0_SB_DQ<27>")
		)
		(pad "281" smd rect
			(at 2.050034 57.375044 90)
			(size 0.519938 1.4986)
			(layers "F.Cu" "F.Mask" "F.Paste")
			(net "GND")
		)
		(pad "282" smd rect
			(at 2.050034 58.224928 90)
			(size 0.519938 1.4986)
			(layers "F.Cu" "F.Mask" "F.Paste")
			(net "M_C_CPU0_SB_DQS_DN<8>")
		)
		(pad "283" smd rect
			(at 2.050034 59.075066 90)
			(size 0.519938 1.4986)
			(layers "F.Cu" "F.Mask" "F.Paste")
			(net "M_C_CPU0_SB_DQS_DP<8>")
		)
		(pad "284" smd rect
			(at 2.050034 59.92495 90)
			(size 0.519938 1.4986)
			(layers "F.Cu" "F.Mask" "F.Paste")
			(net "GND")
		)
		(pad "285" smd rect
			(at 2.050034 60.775088 90)
			(size 0.519938 1.4986)
			(layers "F.Cu" "F.Mask" "F.Paste")
			(net "M_C_CPU0_SB_DQ<30>")
		)
		(pad "286" smd rect
			(at 2.050034 61.624972 90)
			(size 0.519938 1.4986)
			(layers "F.Cu" "F.Mask" "F.Paste")
			(net "GND")
		)
		(pad "287" smd rect
			(at 2.050034 62.47511 90)
			(size 0.519938 1.4986)
			(layers "F.Cu" "F.Mask" "F.Paste")
			(net "M_C_CPU0_SB_DQ<31>")
		)
		(pad "288" smd rect
			(at 2.050034 63.324994 90)
			(size 0.519938 1.4986)
			(layers "F.Cu" "F.Mask" "F.Paste")
			(net "GND")
		)
		(pad "G1" thru_hole oval
			(at 0 -68.97497 90)
			(size 1.7272 3.4798)
			(drill oval 1.2192 2.4638)
			(layers "*.Cu" "*.Mask")
			(remove_unused_layers no)
			(net "GND")
			(clearance 0.127)
			(thermal_gap 0.127)
		)
		(pad "G2" thru_hole oval
			(at 0 3.875024 90)
			(size 1.7272 3.4798)
			(drill oval 1.2192 2.4638)
			(layers "*.Cu" "*.Mask")
			(remove_unused_layers no)
			(net "GND")
			(clearance 0.127)
			(thermal_gap 0.127)
		)
		(pad "G3" thru_hole oval
			(at 0 68.97497 90)
			(size 1.7272 3.4798)
			(drill oval 1.2192 2.4638)
			(layers "*.Cu" "*.Mask")
			(remove_unused_layers no)
			(net "GND")
			(clearance 0.127)
			(thermal_gap 0.127)
		)
	)
)
